(kicad_pcb
	(version 20260206)
	(generator "pcbnew")
	(generator_version "10.0")
	(general
		(thickness 1.6)
		(legacy_teardrops no)
	)
	(paper "A4")
	(title_block
		(title "panther-plus-userver — 13130-1b_20150205.brd")
		(comment 1 "Honey Badger (Wiwynn) / footprint 894 of 1509 (DIMM1), pads 30-36 of 210")
	)
	(layers
		(0 "F.Cu" signal "TOP")
		(4 "In1.Cu" signal "L2")
		(6 "In2.Cu" signal "L3")
		(8 "In3.Cu" signal "L4")
		(10 "In4.Cu" signal "L5")
		(12 "In5.Cu" signal "L6")
		(14 "In6.Cu" signal "L7")
		(16 "In7.Cu" signal "L8")
		(18 "In8.Cu" signal "L9")
		(20 "In9.Cu" signal "L10")
		(22 "In10.Cu" signal "L11")
		(2 "B.Cu" signal "BOTTOM")
		(9 "F.Adhes" user "F.Adhesive")
		(11 "B.Adhes" user "B.Adhesive")
		(13 "F.Paste" user "Package Geometry/Pastemask Top")
		(15 "B.Paste" user "Package Geometry/Pastemask Bottom")
		(5 "F.SilkS" user "Ref Des/Silkscreen Top")
		(7 "B.SilkS" user "Ref Des/Silkscreen Bottom")
		(1 "F.Mask" user "Board Geometry/Soldermask Top")
		(3 "B.Mask" user "Board Geometry/Soldermask Bottom")
		(17 "Dwgs.User" user "User.Drawings")
		(19 "Cmts.User" user "User.Comments")
		(21 "Eco1.User" user "User.Eco1")
		(23 "Eco2.User" user "User.Eco2")
		(25 "Edge.Cuts" user "Board Geometry/Outline")
		(27 "Margin" user)
		(31 "F.CrtYd" user "Package Geometry/Place Bound Top")
		(29 "B.CrtYd" user "Package Geometry/Place Bound Bottom")
		(35 "F.Fab" user "Ref Des/Assembly Top")
		(33 "B.Fab" user "Ref Des/Assembly Bottom")
	)
	(footprint ""
		(layer "B.Cu")
		(at 158.500064 -66.699892 180)
		(property "Reference" "DIMM1"
			(at 0 0 0)
			(layer "B.SilkS")
			(hide yes)
			(effects
				(font
					(size 1.27 1.27)
				)
				(justify mirror)
			)
		)
		(property "Value" "DDR3-204P-142-COLAY-1-GP-U"
			(at 41.312338 -16.676878 180)
			(unlocked yes)
			(layer "B.Fab")
			(hide yes)
			(effects
				(font
					(size 1.016 1.016)
					(thickness 0.1524)
				)
				(justify mirror)
			)
		)
		(property "Device Type" "AS0A626-J8R6-7H-COLAY-1"
			(at 41.312338 -18.200878 180)
			(unlocked yes)
			(layer "B.Fab")
			(hide yes)
			(effects
				(font
					(size 1.016 1.016)
					(thickness 0.1524)
				)
				(justify mirror)
			)
		)
		(duplicate_pad_numbers_are_jumpers no)
		(pad "28" smd custom
			(at -23.550118 4.100068)
			(size 0.1143 0.1143)
			(layers "B.Cu" "B.Mask" "B.Paste")
			(net "GND")
			(options
				(clearance outline)
				(anchor circle)
			)
			(primitives
				(gr_poly
					(pts
						(xy 0 -0.9017) (xy -0.03175 -0.89916) (xy -0.0635 -0.889) (xy -0.09144 -0.87376) (xy -0.11684 -0.85344)
						(xy -0.13716 -0.82804) (xy -0.1524 -0.8001) (xy -0.16256 -0.76835) (xy -0.1651 -0.7366) (xy -0.1651 -0.11938)
						(xy -0.17272 -0.11176) (xy -0.19812 -0.0762) (xy -0.2032 -0.06604) (xy -0.20701 -0.05715) (xy -0.21209 -0.04699)
						(xy -0.2159 -0.03683) (xy -0.21844 -0.02667) (xy -0.22225 -0.01524) (xy -0.22352 -0.00508) (xy -0.22606 0.00508)
						(xy -0.22733 0.01651) (xy -0.22733 0.02667) (xy -0.2286 0.0381) (xy -0.22733 0.04953) (xy -0.22733 0.05969)
						(xy -0.22606 0.07112) (xy -0.22352 0.08128) (xy -0.22225 0.09144) (xy -0.21844 0.10287) (xy -0.2159 0.11303)
						(xy -0.21209 0.12319) (xy -0.20701 0.13335) (xy -0.2032 0.14224) (xy -0.19812 0.1524) (xy -0.17272 0.18796)
						(xy -0.1651 0.19558) (xy -0.1651 0.7366) (xy -0.16256 0.76835) (xy -0.1524 0.8001) (xy -0.13716 0.82804)
						(xy -0.11684 0.85344) (xy -0.09144 0.87376) (xy -0.0635 0.889) (xy -0.03175 0.89916) (xy 0 0.9017)
						(xy 0.03175 0.89916) (xy 0.0635 0.889) (xy 0.09144 0.87376) (xy 0.11684 0.85344) (xy 0.13716 0.82804)
						(xy 0.1524 0.8001) (xy 0.16256 0.76835) (xy 0.1651 0.7366) (xy 0.1651 0.19685) (xy 0.17272 0.18923)
						(xy 0.17907 0.18034) (xy 0.18669 0.17145) (xy 0.19177 0.16256) (xy 0.19812 0.15367) (xy 0.20828 0.13335)
						(xy 0.21971 0.10287) (xy 0.22225 0.09271) (xy 0.22479 0.08128) (xy 0.22606 0.07112) (xy 0.2286 0.05969)
						(xy 0.2286 0.01651) (xy 0.22606 0.00508) (xy 0.22479 -0.00508) (xy 0.22225 -0.01651) (xy 0.21971 -0.02667)
						(xy 0.20828 -0.05715) (xy 0.19812 -0.07747) (xy 0.19177 -0.08636) (xy 0.18669 -0.09525) (xy 0.17907 -0.10414)
						(xy 0.17272 -0.11303) (xy 0.1651 -0.12065) (xy 0.1651 -0.7366) (xy 0.16256 -0.76835) (xy 0.1524 -0.8001)
						(xy 0.13716 -0.82804) (xy 0.11684 -0.85344) (xy 0.09144 -0.87376) (xy 0.0635 -0.889) (xy 0.03175 -0.89916)
					)
					(width 0)
					(fill yes)
				)
			)
		)
		(pad "29" smd custom
			(at -23.24989 -4.100068)
			(size 0.1143 0.1143)
			(layers "B.Cu" "B.Mask" "B.Paste")
			(net "GND")
			(options
				(clearance outline)
				(anchor circle)
			)
			(primitives
				(gr_poly
					(pts
						(xy 0 -0.9017) (xy -0.03175 -0.89916) (xy -0.0635 -0.889) (xy -0.09144 -0.87376) (xy -0.11684 -0.85344)
						(xy -0.13716 -0.82804) (xy -0.1524 -0.8001) (xy -0.16256 -0.76835) (xy -0.1651 -0.7366) (xy -0.1651 -0.44958)
						(xy -0.17272 -0.44196) (xy -0.19812 -0.4064) (xy -0.2032 -0.39624) (xy -0.20701 -0.38735) (xy -0.21209 -0.37719)
						(xy -0.2159 -0.36703) (xy -0.21844 -0.35687) (xy -0.22225 -0.34544) (xy -0.22352 -0.33528) (xy -0.22606 -0.32512)
						(xy -0.22733 -0.31369) (xy -0.22733 -0.30353) (xy -0.2286 -0.2921) (xy -0.22733 -0.28067) (xy -0.22733 -0.27051)
						(xy -0.22606 -0.25908) (xy -0.22352 -0.24892) (xy -0.22225 -0.23876) (xy -0.21844 -0.22733) (xy -0.2159 -0.21717)
						(xy -0.21209 -0.20701) (xy -0.20701 -0.19685) (xy -0.2032 -0.18796) (xy -0.19812 -0.1778) (xy -0.17272 -0.14224)
						(xy -0.1651 -0.13462) (xy -0.1651 0.7366) (xy -0.16256 0.76835) (xy -0.1524 0.8001) (xy -0.13716 0.82804)
						(xy -0.11684 0.85344) (xy -0.09144 0.87376) (xy -0.0635 0.889) (xy -0.03175 0.89916) (xy 0 0.9017)
						(xy 0.03175 0.89916) (xy 0.0635 0.889) (xy 0.09144 0.87376) (xy 0.11684 0.85344) (xy 0.13716 0.82804)
						(xy 0.1524 0.8001) (xy 0.16256 0.76835) (xy 0.1651 0.7366) (xy 0.1651 -0.13462) (xy 0.17272 -0.14224)
						(xy 0.19812 -0.1778) (xy 0.2032 -0.18796) (xy 0.20701 -0.19685) (xy 0.21209 -0.20701) (xy 0.2159 -0.21717)
						(xy 0.21844 -0.22733) (xy 0.22225 -0.23876) (xy 0.22352 -0.24892) (xy 0.22606 -0.25908) (xy 0.22733 -0.27051)
						(xy 0.22733 -0.28067) (xy 0.2286 -0.2921) (xy 0.22733 -0.30353) (xy 0.22733 -0.31369) (xy 0.22606 -0.32512)
						(xy 0.22352 -0.33528) (xy 0.22225 -0.34544) (xy 0.21844 -0.35687) (xy 0.2159 -0.36703) (xy 0.21209 -0.37719)
						(xy 0.20701 -0.38735) (xy 0.2032 -0.39624) (xy 0.19812 -0.4064) (xy 0.17272 -0.44196) (xy 0.1651 -0.44958)
						(xy 0.1651 -0.7366) (xy 0.16256 -0.76835) (xy 0.1524 -0.8001) (xy 0.13716 -0.82804) (xy 0.11684 -0.85344)
						(xy 0.09144 -0.87376) (xy 0.0635 -0.889) (xy 0.03175 -0.89916)
					)
					(width 0)
					(fill yes)
				)
			)
		)
		(pad "30" smd custom
			(at -22.949916 4.100068)
			(size 0.1143 0.1143)
			(layers "B.Cu" "B.Mask" "B.Paste")
			(net "M_A_RESET#")
			(options
				(clearance outline)
				(anchor circle)
			)
			(primitives
				(gr_poly
					(pts
						(xy 0 -0.9017) (xy -0.03175 -0.89916) (xy -0.0635 -0.889) (xy -0.09144 -0.87376) (xy -0.11684 -0.85344)
						(xy -0.13716 -0.82804) (xy -0.1524 -0.8001) (xy -0.16256 -0.76835) (xy -0.1651 -0.7366) (xy -0.1651 0.13462)
						(xy -0.17272 0.14224) (xy -0.19812 0.1778) (xy -0.2032 0.18796) (xy -0.20701 0.19685) (xy -0.21209 0.20701)
						(xy -0.2159 0.21717) (xy -0.21844 0.22733) (xy -0.22225 0.23876) (xy -0.22352 0.24892) (xy -0.22606 0.25908)
						(xy -0.22733 0.27051) (xy -0.22733 0.28067) (xy -0.2286 0.2921) (xy -0.22733 0.30353) (xy -0.22733 0.31369)
						(xy -0.22606 0.32512) (xy -0.22352 0.33528) (xy -0.22225 0.34544) (xy -0.21844 0.35687) (xy -0.2159 0.36703)
						(xy -0.21209 0.37719) (xy -0.20701 0.38735) (xy -0.2032 0.39624) (xy -0.19812 0.4064) (xy -0.17272 0.44196)
						(xy -0.1651 0.44958) (xy -0.1651 0.7366) (xy -0.16256 0.76835) (xy -0.1524 0.8001) (xy -0.13716 0.82804)
						(xy -0.11684 0.85344) (xy -0.09144 0.87376) (xy -0.0635 0.889) (xy -0.03175 0.89916) (xy 0 0.9017)
						(xy 0.03175 0.89916) (xy 0.0635 0.889) (xy 0.09144 0.87376) (xy 0.11684 0.85344) (xy 0.13716 0.82804)
						(xy 0.1524 0.8001) (xy 0.16256 0.76835) (xy 0.1651 0.7366) (xy 0.1651 0.44958) (xy 0.17272 0.44196)
						(xy 0.19812 0.4064) (xy 0.2032 0.39624) (xy 0.20701 0.38735) (xy 0.21209 0.37719) (xy 0.2159 0.36703)
						(xy 0.21844 0.35687) (xy 0.22225 0.34544) (xy 0.22352 0.33528) (xy 0.22606 0.32512) (xy 0.22733 0.31369)
						(xy 0.22733 0.30353) (xy 0.2286 0.2921) (xy 0.22733 0.28067) (xy 0.22733 0.27051) (xy 0.22606 0.25908)
						(xy 0.22352 0.24892) (xy 0.22225 0.23876) (xy 0.21844 0.22733) (xy 0.2159 0.21717) (xy 0.21209 0.20701)
						(xy 0.20701 0.19685) (xy 0.2032 0.18796) (xy 0.19812 0.1778) (xy 0.17272 0.14224) (xy 0.1651 0.13462)
						(xy 0.1651 -0.7366) (xy 0.16256 -0.76835) (xy 0.1524 -0.8001) (xy 0.13716 -0.82804) (xy 0.11684 -0.85344)
						(xy 0.09144 -0.87376) (xy 0.0635 -0.889) (xy 0.03175 -0.89916)
					)
					(width 0)
					(fill yes)
				)
			)
		)
		(pad "31" smd custom
			(at -22.649942 -4.100068)
			(size 0.1143 0.1143)
			(layers "B.Cu" "B.Mask" "B.Paste")
			(net "M_A_DQ10")
			(options
				(clearance outline)
				(anchor circle)
			)
			(primitives
				(gr_poly
					(pts
						(xy 0 -0.9017) (xy -0.03175 -0.89916) (xy -0.0635 -0.889) (xy -0.09144 -0.87376) (xy -0.11684 -0.85344)
						(xy -0.13716 -0.82804) (xy -0.1524 -0.8001) (xy -0.16256 -0.76835) (xy -0.1651 -0.7366) (xy -0.1651 -0.19685)
						(xy -0.17272 -0.18923) (xy -0.17907 -0.18034) (xy -0.18669 -0.17145) (xy -0.19177 -0.16256) (xy -0.19812 -0.15367)
						(xy -0.20828 -0.13335) (xy -0.21971 -0.10287) (xy -0.22225 -0.09271) (xy -0.22479 -0.08128) (xy -0.22606 -0.07112)
						(xy -0.2286 -0.05969) (xy -0.2286 -0.01651) (xy -0.22606 -0.00508) (xy -0.22479 0.00508) (xy -0.22225 0.01651)
						(xy -0.21971 0.02667) (xy -0.20828 0.05715) (xy -0.19812 0.07747) (xy -0.19177 0.08636) (xy -0.18669 0.09525)
						(xy -0.17907 0.10414) (xy -0.17272 0.11303) (xy -0.1651 0.12065) (xy -0.1651 0.7366) (xy -0.16256 0.76835)
						(xy -0.1524 0.8001) (xy -0.13716 0.82804) (xy -0.11684 0.85344) (xy -0.09144 0.87376) (xy -0.0635 0.889)
						(xy -0.03175 0.89916) (xy 0 0.9017) (xy 0.03175 0.89916) (xy 0.0635 0.889) (xy 0.09144 0.87376)
						(xy 0.11684 0.85344) (xy 0.13716 0.82804) (xy 0.1524 0.8001) (xy 0.16256 0.76835) (xy 0.1651 0.7366)
						(xy 0.1651 0.11938) (xy 0.17272 0.11176) (xy 0.19812 0.0762) (xy 0.2032 0.06604) (xy 0.20701 0.05715)
						(xy 0.21209 0.04699) (xy 0.2159 0.03683) (xy 0.21844 0.02667) (xy 0.22225 0.01524) (xy 0.22352 0.00508)
						(xy 0.22606 -0.00508) (xy 0.22733 -0.01651) (xy 0.22733 -0.02667) (xy 0.2286 -0.0381) (xy 0.22733 -0.04953)
						(xy 0.22733 -0.05969) (xy 0.22606 -0.07112) (xy 0.22352 -0.08128) (xy 0.22225 -0.09144) (xy 0.21844 -0.10287)
						(xy 0.2159 -0.11303) (xy 0.21209 -0.12319) (xy 0.20701 -0.13335) (xy 0.2032 -0.14224) (xy 0.19812 -0.1524)
						(xy 0.17272 -0.18796) (xy 0.1651 -0.19558) (xy 0.1651 -0.7366) (xy 0.16256 -0.76835) (xy 0.1524 -0.8001)
						(xy 0.13716 -0.82804) (xy 0.11684 -0.85344) (xy 0.09144 -0.87376) (xy 0.0635 -0.889) (xy 0.03175 -0.89916)
					)
					(width 0)
					(fill yes)
				)
			)
		)
		(pad "32" smd custom
			(at -22.349968 4.100068)
			(size 0.1143 0.1143)
			(layers "B.Cu" "B.Mask" "B.Paste")
			(net "GND")
			(options
				(clearance outline)
				(anchor circle)
			)
			(primitives
				(gr_poly
					(pts
						(xy 0 -0.9017) (xy -0.03175 -0.89916) (xy -0.0635 -0.889) (xy -0.09144 -0.87376) (xy -0.11684 -0.85344)
						(xy -0.13716 -0.82804) (xy -0.1524 -0.8001) (xy -0.16256 -0.76835) (xy -0.1651 -0.7366) (xy -0.1651 -0.11938)
						(xy -0.17272 -0.11176) (xy -0.19812 -0.0762) (xy -0.2032 -0.06604) (xy -0.20701 -0.05715) (xy -0.21209 -0.04699)
						(xy -0.2159 -0.03683) (xy -0.21844 -0.02667) (xy -0.22225 -0.01524) (xy -0.22352 -0.00508) (xy -0.22606 0.00508)
						(xy -0.22733 0.01651) (xy -0.22733 0.02667) (xy -0.2286 0.0381) (xy -0.22733 0.04953) (xy -0.22733 0.05969)
						(xy -0.22606 0.07112) (xy -0.22352 0.08128) (xy -0.22225 0.09144) (xy -0.21844 0.10287) (xy -0.2159 0.11303)
						(xy -0.21209 0.12319) (xy -0.20701 0.13335) (xy -0.2032 0.14224) (xy -0.19812 0.1524) (xy -0.17272 0.18796)
						(xy -0.1651 0.19558) (xy -0.1651 0.7366) (xy -0.16256 0.76835) (xy -0.1524 0.8001) (xy -0.13716 0.82804)
						(xy -0.11684 0.85344) (xy -0.09144 0.87376) (xy -0.0635 0.889) (xy -0.03175 0.89916) (xy 0 0.9017)
						(xy 0.03175 0.89916) (xy 0.0635 0.889) (xy 0.09144 0.87376) (xy 0.11684 0.85344) (xy 0.13716 0.82804)
						(xy 0.1524 0.8001) (xy 0.16256 0.76835) (xy 0.1651 0.7366) (xy 0.1651 0.19685) (xy 0.17272 0.18923)
						(xy 0.17907 0.18034) (xy 0.18669 0.17145) (xy 0.19177 0.16256) (xy 0.19812 0.15367) (xy 0.20828 0.13335)
						(xy 0.21971 0.10287) (xy 0.22225 0.09271) (xy 0.22479 0.08128) (xy 0.22606 0.07112) (xy 0.2286 0.05969)
						(xy 0.2286 0.01651) (xy 0.22606 0.00508) (xy 0.22479 -0.00508) (xy 0.22225 -0.01651) (xy 0.21971 -0.02667)
						(xy 0.20828 -0.05715) (xy 0.19812 -0.07747) (xy 0.19177 -0.08636) (xy 0.18669 -0.09525) (xy 0.17907 -0.10414)
						(xy 0.17272 -0.11303) (xy 0.1651 -0.12065) (xy 0.1651 -0.7366) (xy 0.16256 -0.76835) (xy 0.1524 -0.8001)
						(xy 0.13716 -0.82804) (xy 0.11684 -0.85344) (xy 0.09144 -0.87376) (xy 0.0635 -0.889) (xy 0.03175 -0.89916)
					)
					(width 0)
					(fill yes)
				)
			)
		)
		(pad "33" smd custom
			(at -22.049994 -4.100068)
			(size 0.1143 0.1143)
			(layers "B.Cu" "B.Mask" "B.Paste")
			(net "M_A_DQ11")
			(options
				(clearance outline)
				(anchor circle)
			)
			(primitives
				(gr_poly
					(pts
						(xy 0 -0.9017) (xy -0.03175 -0.89916) (xy -0.0635 -0.889) (xy -0.09144 -0.87376) (xy -0.11684 -0.85344)
						(xy -0.13716 -0.82804) (xy -0.1524 -0.8001) (xy -0.16256 -0.76835) (xy -0.1651 -0.7366) (xy -0.1651 -0.44958)
						(xy -0.17272 -0.44196) (xy -0.19812 -0.4064) (xy -0.2032 -0.39624) (xy -0.20701 -0.38735) (xy -0.21209 -0.37719)
						(xy -0.2159 -0.36703) (xy -0.21844 -0.35687) (xy -0.22225 -0.34544) (xy -0.22352 -0.33528) (xy -0.22606 -0.32512)
						(xy -0.22733 -0.31369) (xy -0.22733 -0.30353) (xy -0.2286 -0.2921) (xy -0.22733 -0.28067) (xy -0.22733 -0.27051)
						(xy -0.22606 -0.25908) (xy -0.22352 -0.24892) (xy -0.22225 -0.23876) (xy -0.21844 -0.22733) (xy -0.2159 -0.21717)
						(xy -0.21209 -0.20701) (xy -0.20701 -0.19685) (xy -0.2032 -0.18796) (xy -0.19812 -0.1778) (xy -0.17272 -0.14224)
						(xy -0.1651 -0.13462) (xy -0.1651 0.7366) (xy -0.16256 0.76835) (xy -0.1524 0.8001) (xy -0.13716 0.82804)
						(xy -0.11684 0.85344) (xy -0.09144 0.87376) (xy -0.0635 0.889) (xy -0.03175 0.89916) (xy 0 0.9017)
						(xy 0.03175 0.89916) (xy 0.0635 0.889) (xy 0.09144 0.87376) (xy 0.11684 0.85344) (xy 0.13716 0.82804)
						(xy 0.1524 0.8001) (xy 0.16256 0.76835) (xy 0.1651 0.7366) (xy 0.1651 -0.13462) (xy 0.17272 -0.14224)
						(xy 0.19812 -0.1778) (xy 0.2032 -0.18796) (xy 0.20701 -0.19685) (xy 0.21209 -0.20701) (xy 0.2159 -0.21717)
						(xy 0.21844 -0.22733) (xy 0.22225 -0.23876) (xy 0.22352 -0.24892) (xy 0.22606 -0.25908) (xy 0.22733 -0.27051)
						(xy 0.22733 -0.28067) (xy 0.2286 -0.2921) (xy 0.22733 -0.30353) (xy 0.22733 -0.31369) (xy 0.22606 -0.32512)
						(xy 0.22352 -0.33528) (xy 0.22225 -0.34544) (xy 0.21844 -0.35687) (xy 0.2159 -0.36703) (xy 0.21209 -0.37719)
						(xy 0.20701 -0.38735) (xy 0.2032 -0.39624) (xy 0.19812 -0.4064) (xy 0.17272 -0.44196) (xy 0.1651 -0.44958)
						(xy 0.1651 -0.7366) (xy 0.16256 -0.76835) (xy 0.1524 -0.8001) (xy 0.13716 -0.82804) (xy 0.11684 -0.85344)
						(xy 0.09144 -0.87376) (xy 0.0635 -0.889) (xy 0.03175 -0.89916)
					)
					(width 0)
					(fill yes)
				)
			)
		)
		(pad "34" smd custom
			(at -21.75002 4.100068)
			(size 0.1143 0.1143)
			(layers "B.Cu" "B.Mask" "B.Paste")
			(net "M_A_DQ14")
			(options
				(clearance outline)
				(anchor circle)
			)
			(primitives
				(gr_poly
					(pts
						(xy 0 -0.9017) (xy -0.03175 -0.89916) (xy -0.0635 -0.889) (xy -0.09144 -0.87376) (xy -0.11684 -0.85344)
						(xy -0.13716 -0.82804) (xy -0.1524 -0.8001) (xy -0.16256 -0.76835) (xy -0.1651 -0.7366) (xy -0.1651 0.13462)
						(xy -0.17272 0.14224) (xy -0.19812 0.1778) (xy -0.2032 0.18796) (xy -0.20701 0.19685) (xy -0.21209 0.20701)
						(xy -0.2159 0.21717) (xy -0.21844 0.22733) (xy -0.22225 0.23876) (xy -0.22352 0.24892) (xy -0.22606 0.25908)
						(xy -0.22733 0.27051) (xy -0.22733 0.28067) (xy -0.2286 0.2921) (xy -0.22733 0.30353) (xy -0.22733 0.31369)
						(xy -0.22606 0.32512) (xy -0.22352 0.33528) (xy -0.22225 0.34544) (xy -0.21844 0.35687) (xy -0.2159 0.36703)
						(xy -0.21209 0.37719) (xy -0.20701 0.38735) (xy -0.2032 0.39624) (xy -0.19812 0.4064) (xy -0.17272 0.44196)
						(xy -0.1651 0.44958) (xy -0.1651 0.7366) (xy -0.16256 0.76835) (xy -0.1524 0.8001) (xy -0.13716 0.82804)
						(xy -0.11684 0.85344) (xy -0.09144 0.87376) (xy -0.0635 0.889) (xy -0.03175 0.89916) (xy 0 0.9017)
						(xy 0.03175 0.89916) (xy 0.0635 0.889) (xy 0.09144 0.87376) (xy 0.11684 0.85344) (xy 0.13716 0.82804)
						(xy 0.1524 0.8001) (xy 0.16256 0.76835) (xy 0.1651 0.7366) (xy 0.1651 0.44958) (xy 0.17272 0.44196)
						(xy 0.19812 0.4064) (xy 0.2032 0.39624) (xy 0.20701 0.38735) (xy 0.21209 0.37719) (xy 0.2159 0.36703)
						(xy 0.21844 0.35687) (xy 0.22225 0.34544) (xy 0.22352 0.33528) (xy 0.22606 0.32512) (xy 0.22733 0.31369)
						(xy 0.22733 0.30353) (xy 0.2286 0.2921) (xy 0.22733 0.28067) (xy 0.22733 0.27051) (xy 0.22606 0.25908)
						(xy 0.22352 0.24892) (xy 0.22225 0.23876) (xy 0.21844 0.22733) (xy 0.2159 0.21717) (xy 0.21209 0.20701)
						(xy 0.20701 0.19685) (xy 0.2032 0.18796) (xy 0.19812 0.1778) (xy 0.17272 0.14224) (xy 0.1651 0.13462)
						(xy 0.1651 -0.7366) (xy 0.16256 -0.76835) (xy 0.1524 -0.8001) (xy 0.13716 -0.82804) (xy 0.11684 -0.85344)
						(xy 0.09144 -0.87376) (xy 0.0635 -0.889) (xy 0.03175 -0.89916)
					)
					(width 0)
					(fill yes)
				)
			)
		)
	)
)
